# S9S_MB_2U (Grand Teton) — schematic netlist excerpt (pin names and nets, part order shuffled) for the footprints in the layout excerpt that follows; sources: Cadence DE-HDL packaged netlist, KiCad conversion of 03242023_DA0F0TMBIJ0_F0T_Motherboard_J_brd_V01_OCP.brd

U344  AP331AWG7  AP331AWG-7 EMPTY  pkg SOT25  page 306
  \in-\  = OC_P2V5_COMP
  GND  = GND
  \in+\  = HSC_OC_VOL
  OUTPUT  = HSC_D_OC_R2
  VCC  = P12V_AUX

C443  Q_CAP  22UF 4V 20% X6S  pkg C0402  page 77 : A = PVCCFA_EHV_CPU1 ; B = GND

(kicad_pcb
	(version 20260206)
	(generator "pcbnew")
	(generator_version "10.0")
	(general
		(thickness 1.6)
		(legacy_teardrops no)
	)
	(paper "A4")
	(title_block
		(title "03242023_DA0F0TMBIJ0_F0T_Motherboard_J_brd_V01_OCP.brd")
		(comment 1 "Grand Teton / footprints 72-73 of 6105")
	)
	(layers
		(0 "F.Cu" signal "TOP")
		(4 "In1.Cu" signal "GND")
		(6 "In2.Cu" signal "IN1")
		(8 "In3.Cu" signal "GND1")
		(10 "In4.Cu" signal "IN2")
		(12 "In5.Cu" signal "GND2")
		(14 "In6.Cu" signal "IN3")
		(16 "In7.Cu" signal "GND3")
		(18 "In8.Cu" signal "VCC")
		(20 "In9.Cu" signal "VCC1")
		(22 "In10.Cu" signal "GND4")
		(24 "In11.Cu" signal "IN4")
		(26 "In12.Cu" signal "GND5")
		(28 "In13.Cu" signal "IN5")
		(30 "In14.Cu" signal "GND6")
		(32 "In15.Cu" signal "IN6")
		(34 "In16.Cu" signal "GND7")
		(2 "B.Cu" signal "BOTTOM")
		(9 "F.Adhes" user "F.Adhesive")
		(11 "B.Adhes" user "B.Adhesive")
		(13 "F.Paste" user "Package Geometry/Pastemask Top")
		(15 "B.Paste" user "Package Geometry/Pastemask Bottom")
		(5 "F.SilkS" user "Ref Des/Silkscreen Top")
		(7 "B.SilkS" user "Ref Des/Silkscreen Bottom")
		(1 "F.Mask" user "Board Geometry/Soldermask Top")
		(3 "B.Mask" user "Board Geometry/Soldermask Bottom")
		(17 "Dwgs.User" user "User.Drawings")
		(19 "Cmts.User" user "User.Comments")
		(21 "Eco1.User" user "User.Eco1")
		(23 "Eco2.User" user "User.Eco2")
		(25 "Edge.Cuts" user "Board Geometry/Outline")
		(27 "Margin" user)
		(31 "F.CrtYd" user "Package Geometry/Place Bound Top")
		(29 "B.CrtYd" user "Package Geometry/Place Bound Bottom")
		(35 "F.Fab" user "Ref Des/Assembly Top")
		(33 "B.Fab" user "Ref Des/Assembly Bottom")
	)
	(footprint ""
		(layer "F.Cu")
		(at 183.45658 -414.76422 90)
		(property "Reference" "U344"
			(at -0.2413 -3.16611 90)
			(unlocked yes)
			(layer "F.SilkS")
			(effects
				(font
					(size 0.7874 0.5842)
					(thickness 0.1524)
				)
			)
		)
		(property "Value" ""
			(at 0 0 90)
			(layer "F.Fab")
			(effects
				(font
					(size 1.27 1.27)
				)
			)
		)
		(duplicate_pad_numbers_are_jumpers no)
		(fp_line
			(start 2.032 -1.549908)
			(end 2.032 1.549908)
			(stroke
				(width 0.1524)
				(type default)
			)
			(layer "F.SilkS")
		)
		(fp_line
			(start 0.508 -1.549908)
			(end 2.032 -1.549908)
			(stroke
				(width 0.1524)
				(type default)
			)
			(layer "F.SilkS")
		)
		(fp_line
			(start -0.508 -1.549908)
			(end 0 -0.762)
			(stroke
				(width 0.1524)
				(type default)
			)
			(layer "F.SilkS")
		)
		(fp_line
			(start -2.032 -1.549908)
			(end -0.508 -1.549908)
			(stroke
				(width 0.1524)
				(type default)
			)
			(layer "F.SilkS")
		)
		(fp_line
			(start 0 -0.762)
			(end 0.508 -1.549908)
			(stroke
				(width 0.1524)
				(type default)
			)
			(layer "F.SilkS")
		)
		(fp_line
			(start 2.032 1.549908)
			(end -2.032 1.549908)
			(stroke
				(width 0.1524)
				(type default)
			)
			(layer "F.SilkS")
		)
		(fp_line
			(start -2.032 1.549908)
			(end -2.032 -1.549908)
			(stroke
				(width 0.1524)
				(type default)
			)
			(layer "F.SilkS")
		)
		(fp_poly
			(pts
				(xy -1.390396 -2.629408) (xy -2.406396 -2.629154) (xy -1.898396 -1.613408)
			)
			(stroke
				(width 0)
				(type default)
			)
			(fill yes)
			(layer "F.SilkS")
		)
		(fp_line
			(start 0.849884 -1.549908)
			(end 0.849884 1.549908)
			(stroke
				(width 0.1)
				(type default)
			)
			(layer "F.Fab")
		)
		(fp_line
			(start -0.849884 -1.549908)
			(end 0.849884 -1.549908)
			(stroke
				(width 0.1)
				(type default)
			)
			(layer "F.Fab")
		)
		(fp_line
			(start 0.849884 1.549908)
			(end -0.849884 1.549908)
			(stroke
				(width 0.1)
				(type default)
			)
			(layer "F.Fab")
		)
		(fp_line
			(start -0.849884 1.549908)
			(end -0.849884 -1.549908)
			(stroke
				(width 0.1)
				(type default)
			)
			(layer "F.Fab")
		)
		(fp_poly
			(pts
				(xy -3.2004 -1.45796) (xy -3.2004 -0.44196) (xy -2.1844 -0.94996)
			)
			(stroke
				(width 0)
				(type default)
			)
			(fill yes)
			(layer "F.Fab")
		)
		(pad "1" smd rect
			(at -1.35001 -0.94996)
			(size 0.6096 1.0668)
			(layers "F.Cu" "F.Mask" "F.Paste")
			(net "OC_P2V5_COMP")
		)
		(pad "2" smd rect
			(at -1.35001 0)
			(size 0.6096 1.0668)
			(layers "F.Cu" "F.Mask" "F.Paste")
			(net "GND")
		)
		(pad "3" smd rect
			(at -1.35001 0.94996)
			(size 0.6096 1.0668)
			(layers "F.Cu" "F.Mask" "F.Paste")
			(net "HSC_OC_VOL")
		)
		(pad "4" smd rect
			(at 1.35001 0.94996)
			(size 0.6096 1.0668)
			(layers "F.Cu" "F.Mask" "F.Paste")
			(net "HSC_D_OC_R2")
		)
		(pad "5" smd rect
			(at 1.35001 -0.94996)
			(size 0.6096 1.0668)
			(layers "F.Cu" "F.Mask" "F.Paste")
			(net "P12V_AUX")
		)
	)
	(footprint ""
		(layer "F.Cu")
		(at 105.306114 -258.72694 90)
		(property "Reference" "C443"
			(at 0 0 90)
			(layer "F.SilkS")
			(hide yes)
			(effects
				(font
					(size 1.27 1.27)
				)
			)
		)
		(property "Value" ""
			(at 0 0 90)
			(layer "F.Fab")
			(effects
				(font
					(size 1.27 1.27)
				)
			)
		)
		(duplicate_pad_numbers_are_jumpers no)
		(fp_line
			(start 0.7874 -0.4064)
			(end 0.7874 0.4064)
			(stroke
				(width 0.1524)
				(type default)
			)
			(layer "F.SilkS")
		)
		(fp_line
			(start -0.7874 -0.4064)
			(end 0.7874 -0.4064)
			(stroke
				(width 0.1524)
				(type default)
			)
			(layer "F.SilkS")
		)
		(fp_line
			(start 0.7874 0.4064)
			(end -0.7874 0.4064)
			(stroke
				(width 0.1524)
				(type default)
			)
			(layer "F.SilkS")
		)
		(fp_line
			(start -0.7874 0.4064)
			(end -0.7874 -0.4064)
			(stroke
				(width 0.1524)
				(type default)
			)
			(layer "F.SilkS")
		)
		(fp_line
			(start -0.12065 -0.305054)
			(end -0.12065 -0.2794)
			(stroke
				(width 0.1)
				(type default)
			)
			(layer "F.Fab")
		)
		(fp_line
			(start -0.67945 -0.305054)
			(end -0.12065 -0.305054)
			(stroke
				(width 0.1)
				(type default)
			)
			(layer "F.Fab")
		)
		(fp_line
			(start 0.67945 -0.3048)
			(end 0.67945 0.3048)
			(stroke
				(width 0.1)
				(type default)
			)
			(layer "F.Fab")
		)
		(fp_line
			(start 0.12065 -0.3048)
			(end 0.67945 -0.3048)
			(stroke
				(width 0.1)
				(type default)
			)
			(layer "F.Fab")
		)
		(fp_line
			(start 0.12065 -0.2794)
			(end 0.12065 -0.3048)
			(stroke
				(width 0.1)
				(type default)
			)
			(layer "F.Fab")
		)
		(fp_line
			(start -0.12065 -0.2794)
			(end 0.12065 -0.2794)
			(stroke
				(width 0.1)
				(type default)
			)
			(layer "F.Fab")
		)
		(fp_line
			(start 0.120396 0.2794)
			(end -0.12065 0.2794)
			(stroke
				(width 0.1)
				(type default)
			)
			(layer "F.Fab")
		)
		(fp_line
			(start -0.12065 0.2794)
			(end -0.12065 0.3048)
			(stroke
				(width 0.1)
				(type default)
			)
			(layer "F.Fab")
		)
		(fp_line
			(start 0.67945 0.3048)
			(end 0.120396 0.3048)
			(stroke
				(width 0.1)
				(type default)
			)
			(layer "F.Fab")
		)
		(fp_line
			(start 0.120396 0.3048)
			(end 0.120396 0.2794)
			(stroke
				(width 0.1)
				(type default)
			)
			(layer "F.Fab")
		)
		(fp_line
			(start -0.12065 0.3048)
			(end -0.67945 0.3048)
			(stroke
				(width 0.1)
				(type default)
			)
			(layer "F.Fab")
		)
		(fp_line
			(start -0.67945 0.3048)
			(end -0.67945 -0.305054)
			(stroke
				(width 0.1)
				(type default)
			)
			(layer "F.Fab")
		)
		(pad "1" smd circle
			(at -0.40005 0 90)
			(size 0 0)
			(layers "F.Cu" "F.Mask" "F.Paste")
			(net "PVCCFA_EHV_CPU1")
		)
		(pad "2" smd circle
			(at 0.40005 0 90)
			(size 0 0)
			(layers "F.Cu" "F.Mask" "F.Paste")
			(net "GND")
		)
	)
)
